# S9S_MB_2U (Grand Teton) — schematic netlist excerpt (pin names and nets, part order shuffled) for the footprints in the layout excerpt that follows; sources: Cadence DE-HDL packaged netlist, KiCad conversion of 03242023_DA0F0TMBIJ0_F0T_Motherboard_J_brd_V01_OCP.brd

C1542  Q_CAP_DIFFBUS  DIFF BUS_0.22UF 6.3V 20% X6S  pkg C0201  page 177 : \1\ = P5E_CPU1_PE3_TX_C_DN<2> ; \2\ = P5E_CPU1_PE3_TX_DN<2>
PC524  Q_CAP  2.2UF 10V 10% X6S  pkg C0402  page 286 : A = PVCCIN_CPU1_VDD3 ; B = GND
R4275  Q_RES  1K 1% EMPTY  pkg 0402LF  page 169 : A = P3V3_AUX ; B = FM_USB3_1_EQA

(kicad_pcb
	(version 20260206)
	(generator "pcbnew")
	(generator_version "10.0")
	(general
		(thickness 1.6)
		(legacy_teardrops no)
	)
	(paper "A4")
	(title_block
		(title "03242023_DA0F0TMBIJ0_F0T_Motherboard_J_brd_V01_OCP.brd")
		(comment 1 "Grand Teton / footprints 2996-2998 of 6105")
	)
	(layers
		(0 "F.Cu" signal "TOP")
		(4 "In1.Cu" signal "GND")
		(6 "In2.Cu" signal "IN1")
		(8 "In3.Cu" signal "GND1")
		(10 "In4.Cu" signal "IN2")
		(12 "In5.Cu" signal "GND2")
		(14 "In6.Cu" signal "IN3")
		(16 "In7.Cu" signal "GND3")
		(18 "In8.Cu" signal "VCC")
		(20 "In9.Cu" signal "VCC1")
		(22 "In10.Cu" signal "GND4")
		(24 "In11.Cu" signal "IN4")
		(26 "In12.Cu" signal "GND5")
		(28 "In13.Cu" signal "IN5")
		(30 "In14.Cu" signal "GND6")
		(32 "In15.Cu" signal "IN6")
		(34 "In16.Cu" signal "GND7")
		(2 "B.Cu" signal "BOTTOM")
		(9 "F.Adhes" user "F.Adhesive")
		(11 "B.Adhes" user "B.Adhesive")
		(13 "F.Paste" user "Package Geometry/Pastemask Top")
		(15 "B.Paste" user "Package Geometry/Pastemask Bottom")
		(5 "F.SilkS" user "Ref Des/Silkscreen Top")
		(7 "B.SilkS" user "Ref Des/Silkscreen Bottom")
		(1 "F.Mask" user "Board Geometry/Soldermask Top")
		(3 "B.Mask" user "Board Geometry/Soldermask Bottom")
		(17 "Dwgs.User" user "User.Drawings")
		(19 "Cmts.User" user "User.Comments")
		(21 "Eco1.User" user "User.Eco1")
		(23 "Eco2.User" user "User.Eco2")
		(25 "Edge.Cuts" user "Board Geometry/Outline")
		(27 "Margin" user)
		(31 "F.CrtYd" user "Package Geometry/Place Bound Top")
		(29 "B.CrtYd" user "Package Geometry/Place Bound Bottom")
		(35 "F.Fab" user "Ref Des/Assembly Top")
		(33 "B.Fab" user "Ref Des/Assembly Bottom")
	)
	(footprint ""
		(layer "F.Cu")
		(at 109.744002 -336.192368 90)
		(property "Reference" "PC524"
			(at 0 0 90)
			(layer "F.SilkS")
			(hide yes)
			(effects
				(font
					(size 1.27 1.27)
				)
			)
		)
		(property "Value" ""
			(at 0 0 90)
			(layer "F.Fab")
			(effects
				(font
					(size 1.27 1.27)
				)
			)
		)
		(duplicate_pad_numbers_are_jumpers no)
		(fp_line
			(start 0.7874 -0.4064)
			(end 0.7874 0.4064)
			(stroke
				(width 0.1524)
				(type default)
			)
			(layer "F.SilkS")
		)
		(fp_line
			(start -0.7874 -0.4064)
			(end 0.7874 -0.4064)
			(stroke
				(width 0.1524)
				(type default)
			)
			(layer "F.SilkS")
		)
		(fp_line
			(start 0.7874 0.4064)
			(end -0.7874 0.4064)
			(stroke
				(width 0.1524)
				(type default)
			)
			(layer "F.SilkS")
		)
		(fp_line
			(start -0.7874 0.4064)
			(end -0.7874 -0.4064)
			(stroke
				(width 0.1524)
				(type default)
			)
			(layer "F.SilkS")
		)
		(fp_line
			(start -0.12065 -0.305054)
			(end -0.12065 -0.2794)
			(stroke
				(width 0.1)
				(type default)
			)
			(layer "F.Fab")
		)
		(fp_line
			(start -0.67945 -0.305054)
			(end -0.12065 -0.305054)
			(stroke
				(width 0.1)
				(type default)
			)
			(layer "F.Fab")
		)
		(fp_line
			(start 0.67945 -0.3048)
			(end 0.67945 0.3048)
			(stroke
				(width 0.1)
				(type default)
			)
			(layer "F.Fab")
		)
		(fp_line
			(start 0.12065 -0.3048)
			(end 0.67945 -0.3048)
			(stroke
				(width 0.1)
				(type default)
			)
			(layer "F.Fab")
		)
		(fp_line
			(start 0.12065 -0.2794)
			(end 0.12065 -0.3048)
			(stroke
				(width 0.1)
				(type default)
			)
			(layer "F.Fab")
		)
		(fp_line
			(start -0.12065 -0.2794)
			(end 0.12065 -0.2794)
			(stroke
				(width 0.1)
				(type default)
			)
			(layer "F.Fab")
		)
		(fp_line
			(start 0.120396 0.2794)
			(end -0.12065 0.2794)
			(stroke
				(width 0.1)
				(type default)
			)
			(layer "F.Fab")
		)
		(fp_line
			(start -0.12065 0.2794)
			(end -0.12065 0.3048)
			(stroke
				(width 0.1)
				(type default)
			)
			(layer "F.Fab")
		)
		(fp_line
			(start 0.67945 0.3048)
			(end 0.120396 0.3048)
			(stroke
				(width 0.1)
				(type default)
			)
			(layer "F.Fab")
		)
		(fp_line
			(start 0.120396 0.3048)
			(end 0.120396 0.2794)
			(stroke
				(width 0.1)
				(type default)
			)
			(layer "F.Fab")
		)
		(fp_line
			(start -0.12065 0.3048)
			(end -0.67945 0.3048)
			(stroke
				(width 0.1)
				(type default)
			)
			(layer "F.Fab")
		)
		(fp_line
			(start -0.67945 0.3048)
			(end -0.67945 -0.305054)
			(stroke
				(width 0.1)
				(type default)
			)
			(layer "F.Fab")
		)
		(pad "1" smd circle
			(at -0.40005 0 90)
			(size 0 0)
			(layers "F.Cu" "F.Mask" "F.Paste")
			(net "PVCCIN_CPU1_VDD3")
		)
		(pad "2" smd circle
			(at 0.40005 0 90)
			(size 0 0)
			(layers "F.Cu" "F.Mask" "F.Paste")
			(net "GND")
		)
	)
	(footprint ""
		(layer "F.Cu")
		(at 161.297874 -408.517344 -90)
		(property "Reference" "C1542"
			(at 0 0 270)
			(layer "F.SilkS")
			(hide yes)
			(effects
				(font
					(size 1.27 1.27)
				)
			)
		)
		(property "Value" ""
			(at 0 0 270)
			(layer "F.Fab")
			(effects
				(font
					(size 1.27 1.27)
				)
			)
		)
		(duplicate_pad_numbers_are_jumpers no)
		(fp_line
			(start -0.299974 0.150114)
			(end -0.299974 -0.150114)
			(stroke
				(width 0.1)
				(type default)
			)
			(layer "F.Fab")
		)
		(fp_line
			(start 0.299974 0.150114)
			(end -0.299974 0.150114)
			(stroke
				(width 0.1)
				(type default)
			)
			(layer "F.Fab")
		)
		(fp_line
			(start -0.299974 -0.150114)
			(end 0.299974 -0.150114)
			(stroke
				(width 0.1)
				(type default)
			)
			(layer "F.Fab")
		)
		(fp_line
			(start 0.299974 -0.150114)
			(end 0.299974 0.150114)
			(stroke
				(width 0.1)
				(type default)
			)
			(layer "F.Fab")
		)
		(pad "1" smd rect
			(at -0.2667 0 270)
			(size 0.3048 0.381)
			(layers "F.Cu" "F.Mask" "F.Paste")
			(net "P5E_CPU1_PE3_TX_C_DN<2>")
		)
		(pad "2" smd rect
			(at 0.2667 0 270)
			(size 0.3048 0.381)
			(layers "F.Cu" "F.Mask" "F.Paste")
			(net "P5E_CPU1_PE3_TX_DN<2>")
		)
	)
	(footprint ""
		(layer "F.Cu")
		(at 136.61136 -25.189688 180)
		(property "Reference" "R4275"
			(at 0 0 180)
			(layer "F.SilkS")
			(hide yes)
			(effects
				(font
					(size 1.27 1.27)
				)
			)
		)
		(property "Value" ""
			(at 0 0 180)
			(layer "F.Fab")
			(effects
				(font
					(size 1.27 1.27)
				)
			)
		)
		(duplicate_pad_numbers_are_jumpers no)
		(fp_line
			(start 0.7874 0.4064)
			(end -0.7874 0.4064)
			(stroke
				(width 0.1524)
				(type default)
			)
			(layer "F.SilkS")
		)
		(fp_line
			(start 0.7874 -0.4064)
			(end 0.7874 0.4064)
			(stroke
				(width 0.1524)
				(type default)
			)
			(layer "F.SilkS")
		)
		(fp_line
			(start -0.7874 0.4064)
			(end -0.7874 -0.4064)
			(stroke
				(width 0.1524)
				(type default)
			)
			(layer "F.SilkS")
		)
		(fp_line
			(start -0.7874 -0.4064)
			(end 0.7874 -0.4064)
			(stroke
				(width 0.1524)
				(type default)
			)
			(layer "F.SilkS")
		)
		(fp_line
			(start 0.67945 0.3048)
			(end 0.120396 0.3048)
			(stroke
				(width 0.1)
				(type default)
			)
			(layer "F.Fab")
		)
		(fp_line
			(start 0.67945 -0.3048)
			(end 0.67945 0.3048)
			(stroke
				(width 0.1)
				(type default)
			)
			(layer "F.Fab")
		)
		(fp_line
			(start 0.12065 -0.2794)
			(end 0.12065 -0.3048)
			(stroke
				(width 0.1)
				(type default)
			)
			(layer "F.Fab")
		)
		(fp_line
			(start 0.12065 -0.3048)
			(end 0.67945 -0.3048)
			(stroke
				(width 0.1)
				(type default)
			)
			(layer "F.Fab")
		)
		(fp_line
			(start 0.120396 0.3048)
			(end 0.120396 0.2794)
			(stroke
				(width 0.1)
				(type default)
			)
			(layer "F.Fab")
		)
		(fp_line
			(start 0.120396 0.2794)
			(end -0.12065 0.2794)
			(stroke
				(width 0.1)
				(type default)
			)
			(layer "F.Fab")
		)
		(fp_line
			(start -0.12065 0.3048)
			(end -0.67945 0.3048)
			(stroke
				(width 0.1)
				(type default)
			)
			(layer "F.Fab")
		)
		(fp_line
			(start -0.12065 0.2794)
			(end -0.12065 0.3048)
			(stroke
				(width 0.1)
				(type default)
			)
			(layer "F.Fab")
		)
		(fp_line
			(start -0.12065 -0.2794)
			(end 0.12065 -0.2794)
			(stroke
				(width 0.1)
				(type default)
			)
			(layer "F.Fab")
		)
		(fp_line
			(start -0.12065 -0.305054)
			(end -0.12065 -0.2794)
			(stroke
				(width 0.1)
				(type default)
			)
			(layer "F.Fab")
		)
		(fp_line
			(start -0.67945 0.3048)
			(end -0.67945 -0.305054)
			(stroke
				(width 0.1)
				(type default)
			)
			(layer "F.Fab")
		)
		(fp_line
			(start -0.67945 -0.305054)
			(end -0.12065 -0.305054)
			(stroke
				(width 0.1)
				(type default)
			)
			(layer "F.Fab")
		)
		(pad "1" smd circle
			(at -0.40005 0 180)
			(size 0 0)
			(layers "F.Cu" "F.Mask" "F.Paste")
			(net "P3V3_AUX")
		)
		(pad "2" smd circle
			(at 0.40005 0 180)
			(size 0 0)
			(layers "F.Cu" "F.Mask" "F.Paste")
			(net "FM_USB3_1_EQA")
		)
	)
)
